# S9S_MB_2U (Grand Teton) — schematic netlist excerpt (pin names and nets, part order shuffled) for the footprints in the layout excerpt that follows; sources: Cadence DE-HDL packaged netlist, KiCad conversion of 03242023_DA0F0TMBIJ0_F0T_Motherboard_J_brd_V01_OCP.brd

R3340  Q_RES  33.2 1% CHIP  pkg 0402LF  page 241 : A = SMB_HOST_CLK_3V3AUX_SCL ; B = SMB_HOST_CLK_GEN2_3V3AUX_SCL
C338  Q_CAP  47UF 4V 20% X6S  pkg C0805  page 78 : A = PVCCIN_CPU1 ; B = GND
R135  Q_RES  100 1% CHIP  pkg 0402LF  page 125 : A = PWRGD_DRAMPWRGD_CPU1_AB_LVC1_R2 ; B = PVCCD_HV_CPU1

(kicad_pcb
	(version 20260206)
	(generator "pcbnew")
	(generator_version "10.0")
	(general
		(thickness 1.6)
		(legacy_teardrops no)
	)
	(paper "A4")
	(title_block
		(title "03242023_DA0F0TMBIJ0_F0T_Motherboard_J_brd_V01_OCP.brd")
		(comment 1 "Grand Teton / footprints 4637-4639 of 6105")
	)
	(layers
		(0 "F.Cu" signal "TOP")
		(4 "In1.Cu" signal "GND")
		(6 "In2.Cu" signal "IN1")
		(8 "In3.Cu" signal "GND1")
		(10 "In4.Cu" signal "IN2")
		(12 "In5.Cu" signal "GND2")
		(14 "In6.Cu" signal "IN3")
		(16 "In7.Cu" signal "GND3")
		(18 "In8.Cu" signal "VCC")
		(20 "In9.Cu" signal "VCC1")
		(22 "In10.Cu" signal "GND4")
		(24 "In11.Cu" signal "IN4")
		(26 "In12.Cu" signal "GND5")
		(28 "In13.Cu" signal "IN5")
		(30 "In14.Cu" signal "GND6")
		(32 "In15.Cu" signal "IN6")
		(34 "In16.Cu" signal "GND7")
		(2 "B.Cu" signal "BOTTOM")
		(9 "F.Adhes" user "F.Adhesive")
		(11 "B.Adhes" user "B.Adhesive")
		(13 "F.Paste" user "Package Geometry/Pastemask Top")
		(15 "B.Paste" user "Package Geometry/Pastemask Bottom")
		(5 "F.SilkS" user "Ref Des/Silkscreen Top")
		(7 "B.SilkS" user "Ref Des/Silkscreen Bottom")
		(1 "F.Mask" user "Board Geometry/Soldermask Top")
		(3 "B.Mask" user "Board Geometry/Soldermask Bottom")
		(17 "Dwgs.User" user "User.Drawings")
		(19 "Cmts.User" user "User.Comments")
		(21 "Eco1.User" user "User.Eco1")
		(23 "Eco2.User" user "User.Eco2")
		(25 "Edge.Cuts" user "Board Geometry/Outline")
		(27 "Margin" user)
		(31 "F.CrtYd" user "Package Geometry/Place Bound Top")
		(29 "B.CrtYd" user "Package Geometry/Place Bound Bottom")
		(35 "F.Fab" user "Ref Des/Assembly Top")
		(33 "B.Fab" user "Ref Des/Assembly Bottom")
	)
	(footprint ""
		(layer "B.Cu")
		(at 246.8499 -96.761808)
		(property "Reference" "R3340"
			(at 0 0 0)
			(layer "B.SilkS")
			(hide yes)
			(effects
				(font
					(size 1.27 1.27)
				)
				(justify mirror)
			)
		)
		(property "Value" ""
			(at 0 0 0)
			(layer "B.Fab")
			(effects
				(font
					(size 1.27 1.27)
				)
				(justify mirror)
			)
		)
		(duplicate_pad_numbers_are_jumpers no)
		(fp_line
			(start -0.7874 -0.4064)
			(end -0.7874 0.4064)
			(stroke
				(width 0.1524)
				(type default)
			)
			(layer "B.SilkS")
		)
		(fp_line
			(start -0.7874 0.4064)
			(end 0.7874 0.4064)
			(stroke
				(width 0.1524)
				(type default)
			)
			(layer "B.SilkS")
		)
		(fp_line
			(start 0.7874 -0.4064)
			(end -0.7874 -0.4064)
			(stroke
				(width 0.1524)
				(type default)
			)
			(layer "B.SilkS")
		)
		(fp_line
			(start 0.7874 0.4064)
			(end 0.7874 -0.4064)
			(stroke
				(width 0.1524)
				(type default)
			)
			(layer "B.SilkS")
		)
		(fp_line
			(start -0.67945 -0.3048)
			(end -0.67945 0.3048)
			(stroke
				(width 0.1)
				(type default)
			)
			(layer "B.Fab")
		)
		(fp_line
			(start -0.67945 0.3048)
			(end -0.120396 0.3048)
			(stroke
				(width 0.1)
				(type default)
			)
			(layer "B.Fab")
		)
		(fp_line
			(start -0.12065 -0.3048)
			(end -0.67945 -0.3048)
			(stroke
				(width 0.1)
				(type default)
			)
			(layer "B.Fab")
		)
		(fp_line
			(start -0.12065 -0.2794)
			(end -0.12065 -0.3048)
			(stroke
				(width 0.1)
				(type default)
			)
			(layer "B.Fab")
		)
		(fp_line
			(start -0.120396 0.2794)
			(end 0.12065 0.2794)
			(stroke
				(width 0.1)
				(type default)
			)
			(layer "B.Fab")
		)
		(fp_line
			(start -0.120396 0.3048)
			(end -0.120396 0.2794)
			(stroke
				(width 0.1)
				(type default)
			)
			(layer "B.Fab")
		)
		(fp_line
			(start 0.12065 -0.305054)
			(end 0.12065 -0.2794)
			(stroke
				(width 0.1)
				(type default)
			)
			(layer "B.Fab")
		)
		(fp_line
			(start 0.12065 -0.2794)
			(end -0.12065 -0.2794)
			(stroke
				(width 0.1)
				(type default)
			)
			(layer "B.Fab")
		)
		(fp_line
			(start 0.12065 0.2794)
			(end 0.12065 0.3048)
			(stroke
				(width 0.1)
				(type default)
			)
			(layer "B.Fab")
		)
		(fp_line
			(start 0.12065 0.3048)
			(end 0.67945 0.3048)
			(stroke
				(width 0.1)
				(type default)
			)
			(layer "B.Fab")
		)
		(fp_line
			(start 0.67945 -0.305054)
			(end 0.12065 -0.305054)
			(stroke
				(width 0.1)
				(type default)
			)
			(layer "B.Fab")
		)
		(fp_line
			(start 0.67945 0.3048)
			(end 0.67945 -0.305054)
			(stroke
				(width 0.1)
				(type default)
			)
			(layer "B.Fab")
		)
		(pad "1" smd circle
			(at 0.40005 0 180)
			(size 0 0)
			(layers "B.Cu" "B.Mask" "B.Paste")
			(net "SMB_HOST_CLK_3V3AUX_SCL")
		)
		(pad "2" smd circle
			(at -0.40005 0 180)
			(size 0 0)
			(layers "B.Cu" "B.Mask" "B.Paste")
			(net "SMB_HOST_CLK_GEN2_3V3AUX_SCL")
		)
	)
	(footprint ""
		(layer "B.Cu")
		(at 116.40312 -252.17628 -90)
		(property "Reference" "C338"
			(at 0 0 90)
			(layer "B.SilkS")
			(hide yes)
			(effects
				(font
					(size 1.27 1.27)
				)
				(justify mirror)
			)
		)
		(property "Value" ""
			(at 0 0 90)
			(layer "B.Fab")
			(effects
				(font
					(size 1.27 1.27)
				)
				(justify mirror)
			)
		)
		(duplicate_pad_numbers_are_jumpers no)
		(fp_line
			(start -1.524 0.762)
			(end 1.524 0.762)
			(stroke
				(width 0.1524)
				(type default)
			)
			(layer "B.SilkS")
		)
		(fp_line
			(start 1.524 0.762)
			(end 1.524 -0.762)
			(stroke
				(width 0.1524)
				(type default)
			)
			(layer "B.SilkS")
		)
		(fp_line
			(start -1.524 -0.762)
			(end -1.524 0.762)
			(stroke
				(width 0.1524)
				(type default)
			)
			(layer "B.SilkS")
		)
		(fp_line
			(start 1.524 -0.762)
			(end -1.524 -0.762)
			(stroke
				(width 0.1524)
				(type default)
			)
			(layer "B.SilkS")
		)
		(fp_line
			(start -1.1049 0.724916)
			(end -1.1049 -0.724916)
			(stroke
				(width 0.1)
				(type default)
			)
			(layer "B.Fab")
		)
		(fp_line
			(start 1.1049 0.724916)
			(end -1.1049 0.724916)
			(stroke
				(width 0.1)
				(type default)
			)
			(layer "B.Fab")
		)
		(fp_line
			(start -1.1049 -0.724916)
			(end 1.1049 -0.724916)
			(stroke
				(width 0.1)
				(type default)
			)
			(layer "B.Fab")
		)
		(fp_line
			(start 1.1049 -0.724916)
			(end 1.1049 0.724916)
			(stroke
				(width 0.1)
				(type default)
			)
			(layer "B.Fab")
		)
		(pad "1" smd rect
			(at 0.889 0 270)
			(size 1.016 1.27)
			(layers "B.Cu" "B.Mask" "B.Paste")
			(net "PVCCIN_CPU1")
		)
		(pad "2" smd rect
			(at -0.889 0 270)
			(size 1.016 1.27)
			(layers "B.Cu" "B.Mask" "B.Paste")
			(net "GND")
		)
	)
	(footprint ""
		(layer "B.Cu")
		(at 63.616078 -192.93459 90)
		(property "Reference" "R135"
			(at 0 0 90)
			(layer "B.SilkS")
			(hide yes)
			(effects
				(font
					(size 1.27 1.27)
				)
				(justify mirror)
			)
		)
		(property "Value" ""
			(at 0 0 90)
			(layer "B.Fab")
			(effects
				(font
					(size 1.27 1.27)
				)
				(justify mirror)
			)
		)
		(duplicate_pad_numbers_are_jumpers no)
		(fp_line
			(start 0.7874 -0.4064)
			(end -0.7874 -0.4064)
			(stroke
				(width 0.1524)
				(type default)
			)
			(layer "B.SilkS")
		)
		(fp_line
			(start -0.7874 -0.4064)
			(end -0.7874 0.4064)
			(stroke
				(width 0.1524)
				(type default)
			)
			(layer "B.SilkS")
		)
		(fp_line
			(start 0.7874 0.4064)
			(end 0.7874 -0.4064)
			(stroke
				(width 0.1524)
				(type default)
			)
			(layer "B.SilkS")
		)
		(fp_line
			(start -0.7874 0.4064)
			(end 0.7874 0.4064)
			(stroke
				(width 0.1524)
				(type default)
			)
			(layer "B.SilkS")
		)
		(fp_line
			(start 0.67945 -0.305054)
			(end 0.12065 -0.305054)
			(stroke
				(width 0.1)
				(type default)
			)
			(layer "B.Fab")
		)
		(fp_line
			(start 0.12065 -0.305054)
			(end 0.12065 -0.2794)
			(stroke
				(width 0.1)
				(type default)
			)
			(layer "B.Fab")
		)
		(fp_line
			(start -0.12065 -0.3048)
			(end -0.67945 -0.3048)
			(stroke
				(width 0.1)
				(type default)
			)
			(layer "B.Fab")
		)
		(fp_line
			(start -0.67945 -0.3048)
			(end -0.67945 0.3048)
			(stroke
				(width 0.1)
				(type default)
			)
			(layer "B.Fab")
		)
		(fp_line
			(start 0.12065 -0.2794)
			(end -0.12065 -0.2794)
			(stroke
				(width 0.1)
				(type default)
			)
			(layer "B.Fab")
		)
		(fp_line
			(start -0.12065 -0.2794)
			(end -0.12065 -0.3048)
			(stroke
				(width 0.1)
				(type default)
			)
			(layer "B.Fab")
		)
		(fp_line
			(start 0.12065 0.2794)
			(end 0.12065 0.3048)
			(stroke
				(width 0.1)
				(type default)
			)
			(layer "B.Fab")
		)
		(fp_line
			(start -0.120396 0.2794)
			(end 0.12065 0.2794)
			(stroke
				(width 0.1)
				(type default)
			)
			(layer "B.Fab")
		)
		(fp_line
			(start 0.67945 0.3048)
			(end 0.67945 -0.305054)
			(stroke
				(width 0.1)
				(type default)
			)
			(layer "B.Fab")
		)
		(fp_line
			(start 0.12065 0.3048)
			(end 0.67945 0.3048)
			(stroke
				(width 0.1)
				(type default)
			)
			(layer "B.Fab")
		)
		(fp_line
			(start -0.120396 0.3048)
			(end -0.120396 0.2794)
			(stroke
				(width 0.1)
				(type default)
			)
			(layer "B.Fab")
		)
		(fp_line
			(start -0.67945 0.3048)
			(end -0.120396 0.3048)
			(stroke
				(width 0.1)
				(type default)
			)
			(layer "B.Fab")
		)
		(pad "1" smd circle
			(at 0.40005 0 270)
			(size 0 0)
			(layers "B.Cu" "B.Mask" "B.Paste")
			(net "PWRGD_DRAMPWRGD_CPU1_AB_LVC1_R2")
		)
		(pad "2" smd circle
			(at -0.40005 0 270)
			(size 0 0)
			(layers "B.Cu" "B.Mask" "B.Paste")
			(net "PVCCD_HV_CPU1")
		)
	)
)
